# S9S_MB_2U (Grand Teton) — schematic netlist excerpt (pin names and nets, part order shuffled) for the footprints in the layout excerpt that follows; sources: Cadence DE-HDL packaged netlist, KiCad conversion of 03242023_DA0F0TMBIJ0_F0T_Motherboard_J_brd_V01_OCP.brd

R3320  Q_RES  4.7K 5% CHIP  pkg 0402LF  page 148 : A = P3V3_AUX ; B = GPU_FPGA_READY_N
PC2192  Q_CAP  0.001UF 50V 10% X7R  pkg C0402  page 301 : A = HSC_VTEMP ; B = AGND_HSC

(kicad_pcb
	(version 20260206)
	(generator "pcbnew")
	(generator_version "10.0")
	(general
		(thickness 1.6)
		(legacy_teardrops no)
	)
	(paper "A4")
	(title_block
		(title "03242023_DA0F0TMBIJ0_F0T_Motherboard_J_brd_V01_OCP.brd")
		(comment 1 "Grand Teton / footprints 2714-2715 of 6105")
	)
	(layers
		(0 "F.Cu" signal "TOP")
		(4 "In1.Cu" signal "GND")
		(6 "In2.Cu" signal "IN1")
		(8 "In3.Cu" signal "GND1")
		(10 "In4.Cu" signal "IN2")
		(12 "In5.Cu" signal "GND2")
		(14 "In6.Cu" signal "IN3")
		(16 "In7.Cu" signal "GND3")
		(18 "In8.Cu" signal "VCC")
		(20 "In9.Cu" signal "VCC1")
		(22 "In10.Cu" signal "GND4")
		(24 "In11.Cu" signal "IN4")
		(26 "In12.Cu" signal "GND5")
		(28 "In13.Cu" signal "IN5")
		(30 "In14.Cu" signal "GND6")
		(32 "In15.Cu" signal "IN6")
		(34 "In16.Cu" signal "GND7")
		(2 "B.Cu" signal "BOTTOM")
		(9 "F.Adhes" user "F.Adhesive")
		(11 "B.Adhes" user "B.Adhesive")
		(13 "F.Paste" user "Package Geometry/Pastemask Top")
		(15 "B.Paste" user "Package Geometry/Pastemask Bottom")
		(5 "F.SilkS" user "Ref Des/Silkscreen Top")
		(7 "B.SilkS" user "Ref Des/Silkscreen Bottom")
		(1 "F.Mask" user "Board Geometry/Soldermask Top")
		(3 "B.Mask" user "Board Geometry/Soldermask Bottom")
		(17 "Dwgs.User" user "User.Drawings")
		(19 "Cmts.User" user "User.Comments")
		(21 "Eco1.User" user "User.Eco1")
		(23 "Eco2.User" user "User.Eco2")
		(25 "Edge.Cuts" user "Board Geometry/Outline")
		(27 "Margin" user)
		(31 "F.CrtYd" user "Package Geometry/Place Bound Top")
		(29 "B.CrtYd" user "Package Geometry/Place Bound Bottom")
		(35 "F.Fab" user "Ref Des/Assembly Top")
		(33 "B.Fab" user "Ref Des/Assembly Bottom")
	)
	(footprint ""
		(layer "F.Cu")
		(at 30.748732 -403.695408 180)
		(property "Reference" "R3320"
			(at 0 0 180)
			(layer "F.SilkS")
			(hide yes)
			(effects
				(font
					(size 1.27 1.27)
				)
			)
		)
		(property "Value" ""
			(at 0 0 180)
			(layer "F.Fab")
			(effects
				(font
					(size 1.27 1.27)
				)
			)
		)
		(duplicate_pad_numbers_are_jumpers no)
		(fp_line
			(start 0.7874 0.4064)
			(end -0.7874 0.4064)
			(stroke
				(width 0.1524)
				(type default)
			)
			(layer "F.SilkS")
		)
		(fp_line
			(start 0.7874 -0.4064)
			(end 0.7874 0.4064)
			(stroke
				(width 0.1524)
				(type default)
			)
			(layer "F.SilkS")
		)
		(fp_line
			(start -0.7874 0.4064)
			(end -0.7874 -0.4064)
			(stroke
				(width 0.1524)
				(type default)
			)
			(layer "F.SilkS")
		)
		(fp_line
			(start -0.7874 -0.4064)
			(end 0.7874 -0.4064)
			(stroke
				(width 0.1524)
				(type default)
			)
			(layer "F.SilkS")
		)
		(fp_line
			(start 0.67945 0.3048)
			(end 0.120396 0.3048)
			(stroke
				(width 0.1)
				(type default)
			)
			(layer "F.Fab")
		)
		(fp_line
			(start 0.67945 -0.3048)
			(end 0.67945 0.3048)
			(stroke
				(width 0.1)
				(type default)
			)
			(layer "F.Fab")
		)
		(fp_line
			(start 0.12065 -0.2794)
			(end 0.12065 -0.3048)
			(stroke
				(width 0.1)
				(type default)
			)
			(layer "F.Fab")
		)
		(fp_line
			(start 0.12065 -0.3048)
			(end 0.67945 -0.3048)
			(stroke
				(width 0.1)
				(type default)
			)
			(layer "F.Fab")
		)
		(fp_line
			(start 0.120396 0.3048)
			(end 0.120396 0.2794)
			(stroke
				(width 0.1)
				(type default)
			)
			(layer "F.Fab")
		)
		(fp_line
			(start 0.120396 0.2794)
			(end -0.12065 0.2794)
			(stroke
				(width 0.1)
				(type default)
			)
			(layer "F.Fab")
		)
		(fp_line
			(start -0.12065 0.3048)
			(end -0.67945 0.3048)
			(stroke
				(width 0.1)
				(type default)
			)
			(layer "F.Fab")
		)
		(fp_line
			(start -0.12065 0.2794)
			(end -0.12065 0.3048)
			(stroke
				(width 0.1)
				(type default)
			)
			(layer "F.Fab")
		)
		(fp_line
			(start -0.12065 -0.2794)
			(end 0.12065 -0.2794)
			(stroke
				(width 0.1)
				(type default)
			)
			(layer "F.Fab")
		)
		(fp_line
			(start -0.12065 -0.305054)
			(end -0.12065 -0.2794)
			(stroke
				(width 0.1)
				(type default)
			)
			(layer "F.Fab")
		)
		(fp_line
			(start -0.67945 0.3048)
			(end -0.67945 -0.305054)
			(stroke
				(width 0.1)
				(type default)
			)
			(layer "F.Fab")
		)
		(fp_line
			(start -0.67945 -0.305054)
			(end -0.12065 -0.305054)
			(stroke
				(width 0.1)
				(type default)
			)
			(layer "F.Fab")
		)
		(pad "1" smd circle
			(at -0.40005 0 180)
			(size 0 0)
			(layers "F.Cu" "F.Mask" "F.Paste")
			(net "P3V3_AUX")
		)
		(pad "2" smd circle
			(at 0.40005 0 180)
			(size 0 0)
			(layers "F.Cu" "F.Mask" "F.Paste")
			(net "GPU_FPGA_READY_N")
		)
	)
	(footprint ""
		(layer "F.Cu")
		(at 179.352448 -405.303482 180)
		(property "Reference" "PC2192"
			(at 0 0 180)
			(layer "F.SilkS")
			(hide yes)
			(effects
				(font
					(size 1.27 1.27)
				)
			)
		)
		(property "Value" ""
			(at 0 0 180)
			(layer "F.Fab")
			(effects
				(font
					(size 1.27 1.27)
				)
			)
		)
		(duplicate_pad_numbers_are_jumpers no)
		(fp_line
			(start 0.7874 0.4064)
			(end -0.7874 0.4064)
			(stroke
				(width 0.1524)
				(type default)
			)
			(layer "F.SilkS")
		)
		(fp_line
			(start 0.7874 -0.4064)
			(end 0.7874 0.4064)
			(stroke
				(width 0.1524)
				(type default)
			)
			(layer "F.SilkS")
		)
		(fp_line
			(start -0.7874 0.4064)
			(end -0.7874 -0.4064)
			(stroke
				(width 0.1524)
				(type default)
			)
			(layer "F.SilkS")
		)
		(fp_line
			(start -0.7874 -0.4064)
			(end 0.7874 -0.4064)
			(stroke
				(width 0.1524)
				(type default)
			)
			(layer "F.SilkS")
		)
		(fp_line
			(start 0.67945 0.3048)
			(end 0.120396 0.3048)
			(stroke
				(width 0.1)
				(type default)
			)
			(layer "F.Fab")
		)
		(fp_line
			(start 0.67945 -0.3048)
			(end 0.67945 0.3048)
			(stroke
				(width 0.1)
				(type default)
			)
			(layer "F.Fab")
		)
		(fp_line
			(start 0.12065 -0.2794)
			(end 0.12065 -0.3048)
			(stroke
				(width 0.1)
				(type default)
			)
			(layer "F.Fab")
		)
		(fp_line
			(start 0.12065 -0.3048)
			(end 0.67945 -0.3048)
			(stroke
				(width 0.1)
				(type default)
			)
			(layer "F.Fab")
		)
		(fp_line
			(start 0.120396 0.3048)
			(end 0.120396 0.2794)
			(stroke
				(width 0.1)
				(type default)
			)
			(layer "F.Fab")
		)
		(fp_line
			(start 0.120396 0.2794)
			(end -0.12065 0.2794)
			(stroke
				(width 0.1)
				(type default)
			)
			(layer "F.Fab")
		)
		(fp_line
			(start -0.12065 0.3048)
			(end -0.67945 0.3048)
			(stroke
				(width 0.1)
				(type default)
			)
			(layer "F.Fab")
		)
		(fp_line
			(start -0.12065 0.2794)
			(end -0.12065 0.3048)
			(stroke
				(width 0.1)
				(type default)
			)
			(layer "F.Fab")
		)
		(fp_line
			(start -0.12065 -0.2794)
			(end 0.12065 -0.2794)
			(stroke
				(width 0.1)
				(type default)
			)
			(layer "F.Fab")
		)
		(fp_line
			(start -0.12065 -0.305054)
			(end -0.12065 -0.2794)
			(stroke
				(width 0.1)
				(type default)
			)
			(layer "F.Fab")
		)
		(fp_line
			(start -0.67945 0.3048)
			(end -0.67945 -0.305054)
			(stroke
				(width 0.1)
				(type default)
			)
			(layer "F.Fab")
		)
		(fp_line
			(start -0.67945 -0.305054)
			(end -0.12065 -0.305054)
			(stroke
				(width 0.1)
				(type default)
			)
			(layer "F.Fab")
		)
		(pad "1" smd circle
			(at -0.40005 0 180)
			(size 0 0)
			(layers "F.Cu" "F.Mask" "F.Paste")
			(net "HSC_VTEMP")
		)
		(pad "2" smd circle
			(at 0.40005 0 180)
			(size 0 0)
			(layers "F.Cu" "F.Mask" "F.Paste")
			(net "AGND_HSC")
		)
	)
)
